(kicad_pcb
	(version 20260206)
	(generator "pcbnew")
	(generator_version "10.0")
	(general
		(thickness 1.6)
		(legacy_teardrops no)
	)
	(paper "A4")
	(title_block
		(title "01162023_DA0F0TEBIF0_F0T_Expander_BD_F_brd_V02_OCP.brd")
		(comment 1 "Grand Teton / footprints 2607-2613 of 9728")
	)
	(layers
		(0 "F.Cu" signal "TOP")
		(4 "In1.Cu" signal "GND")
		(6 "In2.Cu" signal "VCC")
		(8 "In3.Cu" signal "VCC1")
		(10 "In4.Cu" signal "GND1")
		(12 "In5.Cu" signal "IN1")
		(14 "In6.Cu" signal "GND2")
		(16 "In7.Cu" signal "IN2")
		(18 "In8.Cu" signal "GND3")
		(20 "In9.Cu" signal "IN3")
		(22 "In10.Cu" signal "GND4")
		(24 "In11.Cu" signal "IN4")
		(26 "In12.Cu" signal "GND5")
		(28 "In13.Cu" signal "IN5")
		(30 "In14.Cu" signal "GND6")
		(32 "In15.Cu" signal "IN6")
		(34 "In16.Cu" signal "GND7")
		(2 "B.Cu" signal "BOTTOM")
		(9 "F.Adhes" user "F.Adhesive")
		(11 "B.Adhes" user "B.Adhesive")
		(13 "F.Paste" user "Package Geometry/Pastemask Top")
		(15 "B.Paste" user "Package Geometry/Pastemask Bottom")
		(5 "F.SilkS" user "Ref Des/Silkscreen Top")
		(7 "B.SilkS" user "Ref Des/Silkscreen Bottom")
		(1 "F.Mask" user "Board Geometry/Soldermask Top")
		(3 "B.Mask" user "Board Geometry/Soldermask Bottom")
		(17 "Dwgs.User" user "User.Drawings")
		(19 "Cmts.User" user "User.Comments")
		(21 "Eco1.User" user "User.Eco1")
		(23 "Eco2.User" user "User.Eco2")
		(25 "Edge.Cuts" user "Board Geometry/Outline")
		(27 "Margin" user)
		(31 "F.CrtYd" user "Package Geometry/Place Bound Top")
		(29 "B.CrtYd" user "Package Geometry/Place Bound Bottom")
		(35 "F.Fab" user "Ref Des/Assembly Top")
		(33 "B.Fab" user "Ref Des/Assembly Bottom")
	)
	(footprint ""
		(layer "F.Cu")
		(at 136.445244 -94.671642 180)
		(property "Reference" "R1588"
			(at 0 0 180)
			(layer "F.SilkS")
			(hide yes)
			(effects
				(font
					(size 1.27 1.27)
				)
			)
		)
		(property "Value" ""
			(at 0 0 180)
			(layer "F.Fab")
			(effects
				(font
					(size 1.27 1.27)
				)
			)
		)
		(duplicate_pad_numbers_are_jumpers no)
		(fp_line
			(start 0.7874 0.4064)
			(end -0.7874 0.4064)
			(stroke
				(width 0.1524)
				(type default)
			)
			(layer "F.SilkS")
		)
		(fp_line
			(start 0.7874 -0.4064)
			(end 0.7874 0.4064)
			(stroke
				(width 0.1524)
				(type default)
			)
			(layer "F.SilkS")
		)
		(fp_line
			(start -0.7874 0.4064)
			(end -0.7874 -0.4064)
			(stroke
				(width 0.1524)
				(type default)
			)
			(layer "F.SilkS")
		)
		(fp_line
			(start -0.7874 -0.4064)
			(end 0.7874 -0.4064)
			(stroke
				(width 0.1524)
				(type default)
			)
			(layer "F.SilkS")
		)
		(fp_line
			(start 0.67945 0.3048)
			(end 0.120396 0.3048)
			(stroke
				(width 0.1)
				(type default)
			)
			(layer "F.Fab")
		)
		(fp_line
			(start 0.67945 -0.3048)
			(end 0.67945 0.3048)
			(stroke
				(width 0.1)
				(type default)
			)
			(layer "F.Fab")
		)
		(fp_line
			(start 0.12065 -0.2794)
			(end 0.12065 -0.3048)
			(stroke
				(width 0.1)
				(type default)
			)
			(layer "F.Fab")
		)
		(fp_line
			(start 0.12065 -0.3048)
			(end 0.67945 -0.3048)
			(stroke
				(width 0.1)
				(type default)
			)
			(layer "F.Fab")
		)
		(fp_line
			(start 0.120396 0.3048)
			(end 0.120396 0.2794)
			(stroke
				(width 0.1)
				(type default)
			)
			(layer "F.Fab")
		)
		(fp_line
			(start 0.120396 0.2794)
			(end -0.12065 0.2794)
			(stroke
				(width 0.1)
				(type default)
			)
			(layer "F.Fab")
		)
		(fp_line
			(start -0.12065 0.3048)
			(end -0.67945 0.3048)
			(stroke
				(width 0.1)
				(type default)
			)
			(layer "F.Fab")
		)
		(fp_line
			(start -0.12065 0.2794)
			(end -0.12065 0.3048)
			(stroke
				(width 0.1)
				(type default)
			)
			(layer "F.Fab")
		)
		(fp_line
			(start -0.12065 -0.2794)
			(end 0.12065 -0.2794)
			(stroke
				(width 0.1)
				(type default)
			)
			(layer "F.Fab")
		)
		(fp_line
			(start -0.12065 -0.305054)
			(end -0.12065 -0.2794)
			(stroke
				(width 0.1)
				(type default)
			)
			(layer "F.Fab")
		)
		(fp_line
			(start -0.67945 0.3048)
			(end -0.67945 -0.305054)
			(stroke
				(width 0.1)
				(type default)
			)
			(layer "F.Fab")
		)
		(fp_line
			(start -0.67945 -0.305054)
			(end -0.12065 -0.305054)
			(stroke
				(width 0.1)
				(type default)
			)
			(layer "F.Fab")
		)
		(pad "1" smd circle
			(at -0.40005 0 180)
			(size 0 0)
			(layers "F.Cu" "F.Mask" "F.Paste")
			(net "SMB_BIC_I2C9_MUX0_SSD7_R_SDA")
		)
		(pad "2" smd circle
			(at 0.40005 0 180)
			(size 0 0)
			(layers "F.Cu" "F.Mask" "F.Paste")
			(net "SMB_BIC_I2C9_MUX0_SSD7_SDA")
		)
	)
	(footprint ""
		(layer "F.Cu")
		(at 36.638484 -134.923276)
		(property "Reference" "C36"
			(at 0 0 0)
			(layer "F.SilkS")
			(hide yes)
			(effects
				(font
					(size 1.27 1.27)
				)
			)
		)
		(property "Value" ""
			(at 0 0 0)
			(layer "F.Fab")
			(effects
				(font
					(size 1.27 1.27)
				)
			)
		)
		(duplicate_pad_numbers_are_jumpers no)
		(fp_line
			(start -0.299974 -0.150114)
			(end 0.299974 -0.150114)
			(stroke
				(width 0.1)
				(type default)
			)
			(layer "F.Fab")
		)
		(fp_line
			(start -0.299974 0.150114)
			(end -0.299974 -0.150114)
			(stroke
				(width 0.1)
				(type default)
			)
			(layer "F.Fab")
		)
		(fp_line
			(start 0.299974 -0.150114)
			(end 0.299974 0.150114)
			(stroke
				(width 0.1)
				(type default)
			)
			(layer "F.Fab")
		)
		(fp_line
			(start 0.299974 0.150114)
			(end -0.299974 0.150114)
			(stroke
				(width 0.1)
				(type default)
			)
			(layer "F.Fab")
		)
		(pad "1" smd rect
			(at -0.2667 0)
			(size 0.3048 0.381)
			(layers "F.Cu" "F.Mask" "F.Paste")
			(net "P5E_PEX0_STN1_TX_DN<30>")
		)
		(pad "2" smd rect
			(at 0.2667 0)
			(size 0.3048 0.381)
			(layers "F.Cu" "F.Mask" "F.Paste")
			(net "P5E_PEX0_STN1_TX_C_DN<30>")
		)
	)
	(footprint ""
		(layer "F.Cu")
		(at 336.443574 -49.95291 180)
		(property "Reference" "R632"
			(at 0 0 180)
			(layer "F.SilkS")
			(hide yes)
			(effects
				(font
					(size 1.27 1.27)
				)
			)
		)
		(property "Value" ""
			(at 0 0 180)
			(layer "F.Fab")
			(effects
				(font
					(size 1.27 1.27)
				)
			)
		)
		(duplicate_pad_numbers_are_jumpers no)
		(fp_line
			(start 0.7874 0.4064)
			(end -0.7874 0.4064)
			(stroke
				(width 0.1524)
				(type default)
			)
			(layer "F.SilkS")
		)
		(fp_line
			(start 0.7874 -0.4064)
			(end 0.7874 0.4064)
			(stroke
				(width 0.1524)
				(type default)
			)
			(layer "F.SilkS")
		)
		(fp_line
			(start -0.7874 0.4064)
			(end -0.7874 -0.4064)
			(stroke
				(width 0.1524)
				(type default)
			)
			(layer "F.SilkS")
		)
		(fp_line
			(start -0.7874 -0.4064)
			(end 0.7874 -0.4064)
			(stroke
				(width 0.1524)
				(type default)
			)
			(layer "F.SilkS")
		)
		(fp_line
			(start 0.67945 0.3048)
			(end 0.120396 0.3048)
			(stroke
				(width 0.1)
				(type default)
			)
			(layer "F.Fab")
		)
		(fp_line
			(start 0.67945 -0.3048)
			(end 0.67945 0.3048)
			(stroke
				(width 0.1)
				(type default)
			)
			(layer "F.Fab")
		)
		(fp_line
			(start 0.12065 -0.2794)
			(end 0.12065 -0.3048)
			(stroke
				(width 0.1)
				(type default)
			)
			(layer "F.Fab")
		)
		(fp_line
			(start 0.12065 -0.3048)
			(end 0.67945 -0.3048)
			(stroke
				(width 0.1)
				(type default)
			)
			(layer "F.Fab")
		)
		(fp_line
			(start 0.120396 0.3048)
			(end 0.120396 0.2794)
			(stroke
				(width 0.1)
				(type default)
			)
			(layer "F.Fab")
		)
		(fp_line
			(start 0.120396 0.2794)
			(end -0.12065 0.2794)
			(stroke
				(width 0.1)
				(type default)
			)
			(layer "F.Fab")
		)
		(fp_line
			(start -0.12065 0.3048)
			(end -0.67945 0.3048)
			(stroke
				(width 0.1)
				(type default)
			)
			(layer "F.Fab")
		)
		(fp_line
			(start -0.12065 0.2794)
			(end -0.12065 0.3048)
			(stroke
				(width 0.1)
				(type default)
			)
			(layer "F.Fab")
		)
		(fp_line
			(start -0.12065 -0.2794)
			(end 0.12065 -0.2794)
			(stroke
				(width 0.1)
				(type default)
			)
			(layer "F.Fab")
		)
		(fp_line
			(start -0.12065 -0.305054)
			(end -0.12065 -0.2794)
			(stroke
				(width 0.1)
				(type default)
			)
			(layer "F.Fab")
		)
		(fp_line
			(start -0.67945 0.3048)
			(end -0.67945 -0.305054)
			(stroke
				(width 0.1)
				(type default)
			)
			(layer "F.Fab")
		)
		(fp_line
			(start -0.67945 -0.305054)
			(end -0.12065 -0.305054)
			(stroke
				(width 0.1)
				(type default)
			)
			(layer "F.Fab")
		)
		(pad "1" smd circle
			(at -0.40005 0 180)
			(size 0 0)
			(layers "F.Cu" "F.Mask" "F.Paste")
			(net "SMB_BIC_I2C6_MUX_SSD_8_15_ADC_R_SCL")
		)
		(pad "2" smd circle
			(at 0.40005 0 180)
			(size 0 0)
			(layers "F.Cu" "F.Mask" "F.Paste")
			(net "SMB_SSD11_ADC_SCL")
		)
	)
	(footprint ""
		(layer "F.Cu")
		(at 179.625752 -165.670484 -90)
		(property "Reference" "R3307"
			(at 0 0 270)
			(layer "F.SilkS")
			(hide yes)
			(effects
				(font
					(size 1.27 1.27)
				)
			)
		)
		(property "Value" ""
			(at 0 0 270)
			(layer "F.Fab")
			(effects
				(font
					(size 1.27 1.27)
				)
			)
		)
		(duplicate_pad_numbers_are_jumpers no)
		(fp_line
			(start -0.7874 0.4064)
			(end -0.7874 -0.4064)
			(stroke
				(width 0.1524)
				(type default)
			)
			(layer "F.SilkS")
		)
		(fp_line
			(start 0.7874 0.4064)
			(end -0.7874 0.4064)
			(stroke
				(width 0.1524)
				(type default)
			)
			(layer "F.SilkS")
		)
		(fp_line
			(start -0.7874 -0.4064)
			(end 0.7874 -0.4064)
			(stroke
				(width 0.1524)
				(type default)
			)
			(layer "F.SilkS")
		)
		(fp_line
			(start 0.7874 -0.4064)
			(end 0.7874 0.4064)
			(stroke
				(width 0.1524)
				(type default)
			)
			(layer "F.SilkS")
		)
		(fp_line
			(start -0.67945 0.3048)
			(end -0.67945 -0.305054)
			(stroke
				(width 0.1)
				(type default)
			)
			(layer "F.Fab")
		)
		(fp_line
			(start -0.12065 0.3048)
			(end -0.67945 0.3048)
			(stroke
				(width 0.1)
				(type default)
			)
			(layer "F.Fab")
		)
		(fp_line
			(start 0.120396 0.3048)
			(end 0.120396 0.2794)
			(stroke
				(width 0.1)
				(type default)
			)
			(layer "F.Fab")
		)
		(fp_line
			(start 0.67945 0.3048)
			(end 0.120396 0.3048)
			(stroke
				(width 0.1)
				(type default)
			)
			(layer "F.Fab")
		)
		(fp_line
			(start -0.12065 0.2794)
			(end -0.12065 0.3048)
			(stroke
				(width 0.1)
				(type default)
			)
			(layer "F.Fab")
		)
		(fp_line
			(start 0.120396 0.2794)
			(end -0.12065 0.2794)
			(stroke
				(width 0.1)
				(type default)
			)
			(layer "F.Fab")
		)
		(fp_line
			(start -0.12065 -0.2794)
			(end 0.12065 -0.2794)
			(stroke
				(width 0.1)
				(type default)
			)
			(layer "F.Fab")
		)
		(fp_line
			(start 0.12065 -0.2794)
			(end 0.12065 -0.3048)
			(stroke
				(width 0.1)
				(type default)
			)
			(layer "F.Fab")
		)
		(fp_line
			(start 0.12065 -0.3048)
			(end 0.67945 -0.3048)
			(stroke
				(width 0.1)
				(type default)
			)
			(layer "F.Fab")
		)
		(fp_line
			(start 0.67945 -0.3048)
			(end 0.67945 0.3048)
			(stroke
				(width 0.1)
				(type default)
			)
			(layer "F.Fab")
		)
		(fp_line
			(start -0.67945 -0.305054)
			(end -0.12065 -0.305054)
			(stroke
				(width 0.1)
				(type default)
			)
			(layer "F.Fab")
		)
		(fp_line
			(start -0.12065 -0.305054)
			(end -0.12065 -0.2794)
			(stroke
				(width 0.1)
				(type default)
			)
			(layer "F.Fab")
		)
		(pad "1" smd circle
			(at -0.40005 0 270)
			(size 0 0)
			(layers "F.Cu" "F.Mask" "F.Paste")
			(net "FM_SYS_THROTTLE_R")
		)
		(pad "2" smd circle
			(at 0.40005 0 270)
			(size 0 0)
			(layers "F.Cu" "F.Mask" "F.Paste")
			(net "FM_SYS_THROTTLE_NIC3")
		)
	)
	(footprint ""
		(layer "F.Cu")
		(at 229.5398 -231.4194 -90)
		(property "Reference" "R4536"
			(at 0 0 270)
			(layer "F.SilkS")
			(hide yes)
			(effects
				(font
					(size 1.27 1.27)
				)
			)
		)
		(property "Value" ""
			(at 0 0 270)
			(layer "F.Fab")
			(effects
				(font
					(size 1.27 1.27)
				)
			)
		)
		(duplicate_pad_numbers_are_jumpers no)
		(fp_line
			(start -0.7874 0.4064)
			(end -0.7874 -0.4064)
			(stroke
				(width 0.1524)
				(type default)
			)
			(layer "F.SilkS")
		)
		(fp_line
			(start 0.7874 0.4064)
			(end -0.7874 0.4064)
			(stroke
				(width 0.1524)
				(type default)
			)
			(layer "F.SilkS")
		)
		(fp_line
			(start -0.7874 -0.4064)
			(end 0.7874 -0.4064)
			(stroke
				(width 0.1524)
				(type default)
			)
			(layer "F.SilkS")
		)
		(fp_line
			(start 0.7874 -0.4064)
			(end 0.7874 0.4064)
			(stroke
				(width 0.1524)
				(type default)
			)
			(layer "F.SilkS")
		)
		(fp_line
			(start -0.67945 0.3048)
			(end -0.67945 -0.305054)
			(stroke
				(width 0.1)
				(type default)
			)
			(layer "F.Fab")
		)
		(fp_line
			(start -0.12065 0.3048)
			(end -0.67945 0.3048)
			(stroke
				(width 0.1)
				(type default)
			)
			(layer "F.Fab")
		)
		(fp_line
			(start 0.120396 0.3048)
			(end 0.120396 0.2794)
			(stroke
				(width 0.1)
				(type default)
			)
			(layer "F.Fab")
		)
		(fp_line
			(start 0.67945 0.3048)
			(end 0.120396 0.3048)
			(stroke
				(width 0.1)
				(type default)
			)
			(layer "F.Fab")
		)
		(fp_line
			(start -0.12065 0.2794)
			(end -0.12065 0.3048)
			(stroke
				(width 0.1)
				(type default)
			)
			(layer "F.Fab")
		)
		(fp_line
			(start 0.120396 0.2794)
			(end -0.12065 0.2794)
			(stroke
				(width 0.1)
				(type default)
			)
			(layer "F.Fab")
		)
		(fp_line
			(start -0.12065 -0.2794)
			(end 0.12065 -0.2794)
			(stroke
				(width 0.1)
				(type default)
			)
			(layer "F.Fab")
		)
		(fp_line
			(start 0.12065 -0.2794)
			(end 0.12065 -0.3048)
			(stroke
				(width 0.1)
				(type default)
			)
			(layer "F.Fab")
		)
		(fp_line
			(start 0.12065 -0.3048)
			(end 0.67945 -0.3048)
			(stroke
				(width 0.1)
				(type default)
			)
			(layer "F.Fab")
		)
		(fp_line
			(start 0.67945 -0.3048)
			(end 0.67945 0.3048)
			(stroke
				(width 0.1)
				(type default)
			)
			(layer "F.Fab")
		)
		(fp_line
			(start -0.67945 -0.305054)
			(end -0.12065 -0.305054)
			(stroke
				(width 0.1)
				(type default)
			)
			(layer "F.Fab")
		)
		(fp_line
			(start -0.12065 -0.305054)
			(end -0.12065 -0.2794)
			(stroke
				(width 0.1)
				(type default)
			)
			(layer "F.Fab")
		)
		(pad "1" smd circle
			(at -0.40005 0 270)
			(size 0 0)
			(layers "F.Cu" "F.Mask" "F.Paste")
			(net "NIC0_MAIN_PWR_BIC_EN_R")
		)
		(pad "2" smd circle
			(at 0.40005 0 270)
			(size 0 0)
			(layers "F.Cu" "F.Mask" "F.Paste")
			(net "NIC0_MAIN_PWR_BIC_EN")
		)
	)
	(footprint ""
		(layer "F.Cu")
		(at 365.506 -213.995 180)
		(property "Reference" "R4636"
			(at 0 0 180)
			(layer "F.SilkS")
			(hide yes)
			(effects
				(font
					(size 1.27 1.27)
				)
			)
		)
		(property "Value" ""
			(at 0 0 180)
			(layer "F.Fab")
			(effects
				(font
					(size 1.27 1.27)
				)
			)
		)
		(duplicate_pad_numbers_are_jumpers no)
		(fp_line
			(start 0.7874 0.4064)
			(end -0.7874 0.4064)
			(stroke
				(width 0.1524)
				(type default)
			)
			(layer "F.SilkS")
		)
		(fp_line
			(start 0.7874 -0.4064)
			(end 0.7874 0.4064)
			(stroke
				(width 0.1524)
				(type default)
			)
			(layer "F.SilkS")
		)
		(fp_line
			(start -0.7874 0.4064)
			(end -0.7874 -0.4064)
			(stroke
				(width 0.1524)
				(type default)
			)
			(layer "F.SilkS")
		)
		(fp_line
			(start -0.7874 -0.4064)
			(end 0.7874 -0.4064)
			(stroke
				(width 0.1524)
				(type default)
			)
			(layer "F.SilkS")
		)
		(fp_line
			(start 0.67945 0.3048)
			(end 0.120396 0.3048)
			(stroke
				(width 0.1)
				(type default)
			)
			(layer "F.Fab")
		)
		(fp_line
			(start 0.67945 -0.3048)
			(end 0.67945 0.3048)
			(stroke
				(width 0.1)
				(type default)
			)
			(layer "F.Fab")
		)
		(fp_line
			(start 0.12065 -0.2794)
			(end 0.12065 -0.3048)
			(stroke
				(width 0.1)
				(type default)
			)
			(layer "F.Fab")
		)
		(fp_line
			(start 0.12065 -0.3048)
			(end 0.67945 -0.3048)
			(stroke
				(width 0.1)
				(type default)
			)
			(layer "F.Fab")
		)
		(fp_line
			(start 0.120396 0.3048)
			(end 0.120396 0.2794)
			(stroke
				(width 0.1)
				(type default)
			)
			(layer "F.Fab")
		)
		(fp_line
			(start 0.120396 0.2794)
			(end -0.12065 0.2794)
			(stroke
				(width 0.1)
				(type default)
			)
			(layer "F.Fab")
		)
		(fp_line
			(start -0.12065 0.3048)
			(end -0.67945 0.3048)
			(stroke
				(width 0.1)
				(type default)
			)
			(layer "F.Fab")
		)
		(fp_line
			(start -0.12065 0.2794)
			(end -0.12065 0.3048)
			(stroke
				(width 0.1)
				(type default)
			)
			(layer "F.Fab")
		)
		(fp_line
			(start -0.12065 -0.2794)
			(end 0.12065 -0.2794)
			(stroke
				(width 0.1)
				(type default)
			)
			(layer "F.Fab")
		)
		(fp_line
			(start -0.12065 -0.305054)
			(end -0.12065 -0.2794)
			(stroke
				(width 0.1)
				(type default)
			)
			(layer "F.Fab")
		)
		(fp_line
			(start -0.67945 0.3048)
			(end -0.67945 -0.305054)
			(stroke
				(width 0.1)
				(type default)
			)
			(layer "F.Fab")
		)
		(fp_line
			(start -0.67945 -0.305054)
			(end -0.12065 -0.305054)
			(stroke
				(width 0.1)
				(type default)
			)
			(layer "F.Fab")
		)
		(pad "1" smd circle
			(at -0.40005 0 180)
			(size 0 0)
			(layers "F.Cu" "F.Mask" "F.Paste")
			(net "GND")
		)
		(pad "2" smd circle
			(at 0.40005 0 180)
			(size 0 0)
			(layers "F.Cu" "F.Mask" "F.Paste")
			(net "PCA9555_0_PEX0_A1")
		)
	)
	(footprint ""
		(layer "F.Cu")
		(at 72.947276 -19.33956)
		(property "Reference" "C3887"
			(at 0 0 0)
			(layer "F.SilkS")
			(hide yes)
			(effects
				(font
					(size 1.27 1.27)
				)
			)
		)
		(property "Value" ""
			(at 0 0 0)
			(layer "F.Fab")
			(effects
				(font
					(size 1.27 1.27)
				)
			)
		)
		(duplicate_pad_numbers_are_jumpers no)
		(fp_line
			(start -0.7874 -0.4064)
			(end 0.7874 -0.4064)
			(stroke
				(width 0.1524)
				(type default)
			)
			(layer "F.SilkS")
		)
		(fp_line
			(start -0.7874 0.4064)
			(end -0.7874 -0.4064)
			(stroke
				(width 0.1524)
				(type default)
			)
			(layer "F.SilkS")
		)
		(fp_line
			(start 0.7874 -0.4064)
			(end 0.7874 0.4064)
			(stroke
				(width 0.1524)
				(type default)
			)
			(layer "F.SilkS")
		)
		(fp_line
			(start 0.7874 0.4064)
			(end -0.7874 0.4064)
			(stroke
				(width 0.1524)
				(type default)
			)
			(layer "F.SilkS")
		)
		(fp_line
			(start -0.67945 -0.305054)
			(end -0.12065 -0.305054)
			(stroke
				(width 0.1)
				(type default)
			)
			(layer "F.Fab")
		)
		(fp_line
			(start -0.67945 0.3048)
			(end -0.67945 -0.305054)
			(stroke
				(width 0.1)
				(type default)
			)
			(layer "F.Fab")
		)
		(fp_line
			(start -0.12065 -0.305054)
			(end -0.12065 -0.2794)
			(stroke
				(width 0.1)
				(type default)
			)
			(layer "F.Fab")
		)
		(fp_line
			(start -0.12065 -0.2794)
			(end 0.12065 -0.2794)
			(stroke
				(width 0.1)
				(type default)
			)
			(layer "F.Fab")
		)
		(fp_line
			(start -0.12065 0.2794)
			(end -0.12065 0.3048)
			(stroke
				(width 0.1)
				(type default)
			)
			(layer "F.Fab")
		)
		(fp_line
			(start -0.12065 0.3048)
			(end -0.67945 0.3048)
			(stroke
				(width 0.1)
				(type default)
			)
			(layer "F.Fab")
		)
		(fp_line
			(start 0.120396 0.2794)
			(end -0.12065 0.2794)
			(stroke
				(width 0.1)
				(type default)
			)
			(layer "F.Fab")
		)
		(fp_line
			(start 0.120396 0.3048)
			(end 0.120396 0.2794)
			(stroke
				(width 0.1)
				(type default)
			)
			(layer "F.Fab")
		)
		(fp_line
			(start 0.12065 -0.3048)
			(end 0.67945 -0.3048)
			(stroke
				(width 0.1)
				(type default)
			)
			(layer "F.Fab")
		)
		(fp_line
			(start 0.12065 -0.2794)
			(end 0.12065 -0.3048)
			(stroke
				(width 0.1)
				(type default)
			)
			(layer "F.Fab")
		)
		(fp_line
			(start 0.67945 -0.3048)
			(end 0.67945 0.3048)
			(stroke
				(width 0.1)
				(type default)
			)
			(layer "F.Fab")
		)
		(fp_line
			(start 0.67945 0.3048)
			(end 0.120396 0.3048)
			(stroke
				(width 0.1)
				(type default)
			)
			(layer "F.Fab")
		)
		(pad "1" smd circle
			(at -0.40005 0)
			(size 0 0)
			(layers "F.Cu" "F.Mask" "F.Paste")
			(net "P12V_SSD2")
		)
		(pad "2" smd circle
			(at 0.40005 0)
			(size 0 0)
			(layers "F.Cu" "F.Mask" "F.Paste")
			(net "GND")
		)
	)
)
